(kicad_pcb
	(version 20260206)
	(generator "pcbnew")
	(generator_version "10.0")
	(general
		(thickness 1.6)
		(legacy_teardrops no)
	)
	(paper "A4")
	(title_block
		(title "Bryce Canyon_F.DPB_16315-1-OCP.brd")
		(comment 1 "Bryce Canyon / footprints 188-194 of 2223")
	)
	(layers
		(0 "F.Cu" signal "TOP")
		(4 "In1.Cu" signal "L2GND")
		(6 "In2.Cu" signal "L3")
		(8 "In3.Cu" signal "L4GND")
		(10 "In4.Cu" signal "L5")
		(12 "In5.Cu" signal "L6VCC")
		(14 "In6.Cu" signal "L7VCC")
		(16 "In7.Cu" signal "L8")
		(18 "In8.Cu" signal "L9GND")
		(20 "In9.Cu" signal "L10")
		(22 "In10.Cu" signal "L11GND")
		(2 "B.Cu" signal "BOTTOM")
		(9 "F.Adhes" user "F.Adhesive")
		(11 "B.Adhes" user "B.Adhesive")
		(13 "F.Paste" user "Package Geometry/Pastemask Top")
		(15 "B.Paste" user "Package Geometry/Pastemask Bottom")
		(5 "F.SilkS" user "Ref Des/Silkscreen Top")
		(7 "B.SilkS" user "Ref Des/Silkscreen Bottom")
		(1 "F.Mask" user "Board Geometry/Soldermask Top")
		(3 "B.Mask" user "Board Geometry/Soldermask Bottom")
		(17 "Dwgs.User" user "User.Drawings")
		(19 "Cmts.User" user "User.Comments")
		(21 "Eco1.User" user "User.Eco1")
		(23 "Eco2.User" user "User.Eco2")
		(25 "Edge.Cuts" user "Board Geometry/Outline")
		(27 "Margin" user)
		(31 "F.CrtYd" user "Package Geometry/Place Bound Top")
		(29 "B.CrtYd" user "Package Geometry/Place Bound Bottom")
		(35 "F.Fab" user "Ref Des/Assembly Top")
		(33 "B.Fab" user "Ref Des/Assembly Bottom")
	)
	(footprint ""
		(layer "F.Cu")
		(at 95.608902 -277.750016 -90)
		(property "Reference" "VIA38"
			(at 0 0 270)
			(layer "F.SilkS")
			(hide yes)
			(effects
				(font
					(size 1.27 1.27)
				)
			)
		)
		(property "Value" "100OHM-8L-1D6MM-L18L16-GP"
			(at -3.7211 -4.5085 270)
			(unlocked yes)
			(layer "F.Fab")
			(hide yes)
			(effects
				(font
					(size 1.016 1.016)
					(thickness 0.1524)
				)
			)
		)
		(property "Device Type" "VIA-PCIE-4P-394076"
			(at -3.7211 -6.0325 270)
			(unlocked yes)
			(layer "F.Fab")
			(hide yes)
			(effects
				(font
					(size 1.016 1.016)
					(thickness 0.1524)
				)
			)
		)
		(duplicate_pad_numbers_are_jumpers no)
		(fp_rect
			(start -1.9685 0.381)
			(end 1.9685 -0.381)
			(stroke
				(width 0)
				(type default)
			)
			(fill no)
			(layer "F.CrtYd")
		)
		(fp_rect
			(start -1.9685 0.381)
			(end 1.9685 -0.381)
			(stroke
				(width 0)
				(type default)
			)
			(fill no)
			(layer "F.Fab")
		)
		(pad "1" thru_hole circle
			(at -1.5875 0 270)
			(size 0.508 0.508)
			(drill 0.254)
			(layers "*.Cu" "*.Mask")
			(remove_unused_layers no)
			(net "GND")
			(clearance 0.127)
			(thermal_gap 0.127)
		)
		(pad "2" thru_hole circle
			(at -0.5715 0 270)
			(size 0.508 0.508)
			(drill 0.254)
			(layers "*.Cu" "*.Mask")
			(remove_unused_layers no)
			(net "PHY_DRV_A_TO_SCC_A_2_DP")
			(clearance 0.127)
			(thermal_gap 0.127)
		)
		(pad "3" thru_hole circle
			(at 0.5715 0 270)
			(size 0.508 0.508)
			(drill 0.254)
			(layers "*.Cu" "*.Mask")
			(remove_unused_layers no)
			(net "PHY_DRV_A_TO_SCC_A_2_DN")
			(clearance 0.127)
			(thermal_gap 0.127)
		)
		(pad "4" thru_hole circle
			(at 1.5875 0 270)
			(size 0.508 0.508)
			(drill 0.254)
			(layers "*.Cu" "*.Mask")
			(remove_unused_layers no)
			(net "GND")
			(clearance 0.127)
			(thermal_gap 0.127)
		)
	)
	(footprint ""
		(layer "F.Cu")
		(at 128.644396 -283.101542 -90)
		(property "Reference" "C87"
			(at 0 0 270)
			(layer "F.SilkS")
			(hide yes)
			(effects
				(font
					(size 1.27 1.27)
				)
			)
		)
		(property "Value" "SCD033U25V2KX-GP"
			(at 1.1811 -2.7051 270)
			(unlocked yes)
			(layer "F.Fab")
			(hide yes)
			(effects
				(font
					(size 1.016 1.016)
					(thickness 0.1524)
				)
			)
		)
		(property "Device Type" "C402H22"
			(at 1.1811 -4.2291 270)
			(unlocked yes)
			(layer "F.Fab")
			(hide yes)
			(effects
				(font
					(size 1.016 1.016)
					(thickness 0.1524)
				)
			)
		)
		(duplicate_pad_numbers_are_jumpers no)
		(fp_rect
			(start -0.4318 0.9525)
			(end 0.4318 -0.9525)
			(stroke
				(width 0)
				(type default)
			)
			(fill no)
			(layer "F.CrtYd")
		)
		(fp_rect
			(start -0.4318 0.9525)
			(end 0.4318 -0.9525)
			(stroke
				(width 0)
				(type default)
			)
			(fill no)
			(layer "F.Fab")
		)
		(pad "1" smd custom
			(at 0 -0.4445 270)
			(size 0.1524 0.1524)
			(layers "F.Cu" "F.Mask" "F.Paste")
			(net "SW_HDD_P3")
			(options
				(clearance outline)
				(anchor circle)
			)
			(primitives
				(gr_poly
					(pts
						(arc
							(start 0.3048 -0.2032)
							(mid 0.275042 -0.275042)
							(end 0.2032 -0.3048)
						)
						(arc
							(start -0.2032 -0.3048)
							(mid -0.275042 -0.275042)
							(end -0.3048 -0.2032)
						)
						(arc
							(start -0.3048 0.2032)
							(mid -0.275042 0.275042)
							(end -0.2032 0.3048)
						)
						(arc
							(start 0.2032 0.3048)
							(mid 0.275042 0.275042)
							(end 0.3048 0.2032)
						)
					)
					(width 0)
					(fill yes)
				)
			)
		)
		(pad "2" smd custom
			(at 0 0.4445 270)
			(size 0.1524 0.1524)
			(layers "F.Cu" "F.Mask" "F.Paste")
			(net "GND")
			(options
				(clearance outline)
				(anchor circle)
			)
			(primitives
				(gr_poly
					(pts
						(arc
							(start 0.3048 -0.2032)
							(mid 0.275042 -0.275042)
							(end 0.2032 -0.3048)
						)
						(arc
							(start -0.2032 -0.3048)
							(mid -0.275042 -0.275042)
							(end -0.3048 -0.2032)
						)
						(arc
							(start -0.3048 0.2032)
							(mid -0.275042 0.275042)
							(end -0.2032 0.3048)
						)
						(arc
							(start 0.2032 0.3048)
							(mid 0.275042 0.275042)
							(end 0.3048 0.2032)
						)
					)
					(width 0)
					(fill yes)
				)
			)
		)
	)
	(footprint ""
		(layer "F.Cu")
		(at 361.369102 -296.842942 180)
		(property "Reference" "C131"
			(at 0 0 180)
			(layer "F.SilkS")
			(hide yes)
			(effects
				(font
					(size 1.27 1.27)
				)
			)
		)
		(property "Value" "SC1U16V3KX-5GP"
			(at 0 -2.8194 180)
			(unlocked yes)
			(layer "F.Fab")
			(hide yes)
			(effects
				(font
					(size 1.016 1.016)
					(thickness 0.1524)
				)
			)
		)
		(property "Device Type" "C603H36"
			(at 0 -4.3434 180)
			(unlocked yes)
			(layer "F.Fab")
			(hide yes)
			(effects
				(font
					(size 1.016 1.016)
					(thickness 0.1524)
				)
			)
		)
		(duplicate_pad_numbers_are_jumpers no)
		(fp_line
			(start 0.508 0)
			(end -0.508 0)
			(stroke
				(width 0.2032)
				(type default)
			)
			(layer "F.SilkS")
		)
		(fp_rect
			(start -0.5842 1.3335)
			(end 0.5842 -1.3335)
			(stroke
				(width 0)
				(type default)
			)
			(fill no)
			(layer "F.CrtYd")
		)
		(fp_rect
			(start -0.5842 1.3335)
			(end 0.5842 -1.3335)
			(stroke
				(width 0)
				(type default)
			)
			(fill no)
			(layer "F.Fab")
		)
		(pad "1" smd custom
			(at 0 -0.762 180)
			(size 0.2159 0.2159)
			(layers "F.Cu" "F.Mask" "F.Paste")
			(net "P5V_HDD7")
			(options
				(clearance outline)
				(anchor circle)
			)
			(primitives
				(gr_poly
					(pts
						(arc
							(start -0.3302 -0.4318)
							(mid -0.402042 -0.402042)
							(end -0.4318 -0.3302)
						)
						(arc
							(start -0.4318 0.3302)
							(mid -0.402042 0.402042)
							(end -0.3302 0.4318)
						)
						(arc
							(start 0.3302 0.4318)
							(mid 0.402042 0.402042)
							(end 0.4318 0.3302)
						)
						(arc
							(start 0.4318 -0.3302)
							(mid 0.402042 -0.402042)
							(end 0.3302 -0.4318)
						)
					)
					(width 0)
					(fill yes)
				)
			)
		)
		(pad "2" smd custom
			(at 0 0.762 180)
			(size 0.2159 0.2159)
			(layers "F.Cu" "F.Mask" "F.Paste")
			(net "GND")
			(options
				(clearance outline)
				(anchor circle)
			)
			(primitives
				(gr_poly
					(pts
						(arc
							(start -0.3302 -0.4318)
							(mid -0.402042 -0.402042)
							(end -0.4318 -0.3302)
						)
						(arc
							(start -0.4318 0.3302)
							(mid -0.402042 0.402042)
							(end -0.3302 0.4318)
						)
						(arc
							(start 0.3302 0.4318)
							(mid 0.402042 0.402042)
							(end 0.4318 0.3302)
						)
						(arc
							(start 0.4318 -0.3302)
							(mid 0.402042 -0.402042)
							(end 0.3302 -0.4318)
						)
					)
					(width 0)
					(fill yes)
				)
			)
		)
	)
	(footprint ""
		(layer "F.Cu")
		(at 128.644396 -282.085542 90)
		(property "Reference" "R206"
			(at 0 0 90)
			(layer "F.SilkS")
			(hide yes)
			(effects
				(font
					(size 1.27 1.27)
				)
			)
		)
		(property "Value" "4K7R2J-2-GP"
			(at 0.064008 -3.993896 90)
			(unlocked yes)
			(layer "F.Fab")
			(hide yes)
			(effects
				(font
					(size 1.016 1.016)
					(thickness 0.1524)
				)
			)
		)
		(property "Device Type" "R402H16"
			(at 0.064008 -5.517896 90)
			(unlocked yes)
			(layer "F.Fab")
			(hide yes)
			(effects
				(font
					(size 1.016 1.016)
					(thickness 0.1524)
				)
			)
		)
		(duplicate_pad_numbers_are_jumpers no)
		(fp_line
			(start 0.508 -0.9398)
			(end -0.508 -0.9398)
			(stroke
				(width 0.1524)
				(type default)
			)
			(layer "F.SilkS")
		)
		(fp_line
			(start -0.508 -0.9398)
			(end -0.508 0.9398)
			(stroke
				(width 0.1524)
				(type default)
			)
			(layer "F.SilkS")
		)
		(fp_rect
			(start -0.508 0.9398)
			(end 0.508 -0.9398)
			(stroke
				(width 0)
				(type default)
			)
			(fill no)
			(layer "F.CrtYd")
		)
		(fp_rect
			(start -0.508 0.9398)
			(end 0.508 -0.9398)
			(stroke
				(width 0)
				(type default)
			)
			(fill no)
			(layer "F.Fab")
		)
		(pad "1" smd custom
			(at 0 -0.4445 90)
			(size 0.1397 0.1397)
			(layers "F.Cu" "F.Mask" "F.Paste")
			(net "P12V_A")
			(options
				(clearance outline)
				(anchor circle)
			)
			(primitives
				(gr_poly
					(pts
						(arc
							(start -0.1778 -0.2794)
							(mid -0.249642 -0.249642)
							(end -0.2794 -0.1778)
						)
						(arc
							(start -0.2794 0.1778)
							(mid -0.249642 0.249642)
							(end -0.1778 0.2794)
						)
						(arc
							(start 0.1778 0.2794)
							(mid 0.249642 0.249642)
							(end 0.2794 0.1778)
						)
						(arc
							(start 0.2794 -0.1778)
							(mid 0.249642 -0.249642)
							(end 0.1778 -0.2794)
						)
					)
					(width 0)
					(fill yes)
				)
			)
		)
		(pad "2" smd custom
			(at 0 0.4445 90)
			(size 0.1397 0.1397)
			(layers "F.Cu" "F.Mask" "F.Paste")
			(net "SW_HDD_P3")
			(options
				(clearance outline)
				(anchor circle)
			)
			(primitives
				(gr_poly
					(pts
						(arc
							(start -0.1778 -0.2794)
							(mid -0.249642 -0.249642)
							(end -0.2794 -0.1778)
						)
						(arc
							(start -0.2794 0.1778)
							(mid -0.249642 0.249642)
							(end -0.1778 0.2794)
						)
						(arc
							(start 0.1778 0.2794)
							(mid 0.249642 0.249642)
							(end 0.2794 0.1778)
						)
						(arc
							(start 0.2794 -0.1778)
							(mid 0.249642 -0.249642)
							(end 0.1778 -0.2794)
						)
					)
					(width 0)
					(fill yes)
				)
			)
		)
	)
	(footprint ""
		(layer "F.Cu")
		(at 233.299 -382.1938 180)
		(property "Reference" "R1147"
			(at 0 0 180)
			(layer "F.SilkS")
			(hide yes)
			(effects
				(font
					(size 1.27 1.27)
				)
			)
		)
		(property "Value" "10KR2J-3-GP"
			(at 0.064008 -3.993896 180)
			(unlocked yes)
			(layer "F.Fab")
			(hide yes)
			(effects
				(font
					(size 1.016 1.016)
					(thickness 0.1524)
				)
			)
		)
		(property "Device Type" "R402H16"
			(at 0.064008 -5.517896 180)
			(unlocked yes)
			(layer "F.Fab")
			(hide yes)
			(effects
				(font
					(size 1.016 1.016)
					(thickness 0.1524)
				)
			)
		)
		(duplicate_pad_numbers_are_jumpers no)
		(fp_line
			(start 0.508 -0.9398)
			(end -0.508 -0.9398)
			(stroke
				(width 0.1524)
				(type default)
			)
			(layer "F.SilkS")
		)
		(fp_line
			(start -0.508 -0.9398)
			(end -0.508 0.9398)
			(stroke
				(width 0.1524)
				(type default)
			)
			(layer "F.SilkS")
		)
		(fp_rect
			(start -0.508 0.9398)
			(end 0.508 -0.9398)
			(stroke
				(width 0)
				(type default)
			)
			(fill no)
			(layer "F.CrtYd")
		)
		(fp_rect
			(start -0.508 0.9398)
			(end 0.508 -0.9398)
			(stroke
				(width 0)
				(type default)
			)
			(fill no)
			(layer "F.Fab")
		)
		(pad "1" smd custom
			(at 0 -0.4445 180)
			(size 0.1397 0.1397)
			(layers "F.Cu" "F.Mask" "F.Paste")
			(net "GND")
			(options
				(clearance outline)
				(anchor circle)
			)
			(primitives
				(gr_poly
					(pts
						(arc
							(start -0.1778 -0.2794)
							(mid -0.249642 -0.249642)
							(end -0.2794 -0.1778)
						)
						(arc
							(start -0.2794 0.1778)
							(mid -0.249642 0.249642)
							(end -0.1778 0.2794)
						)
						(arc
							(start 0.1778 0.2794)
							(mid 0.249642 0.249642)
							(end 0.2794 0.1778)
						)
						(arc
							(start 0.2794 -0.1778)
							(mid 0.249642 -0.249642)
							(end 0.1778 -0.2794)
						)
					)
					(width 0)
					(fill yes)
				)
			)
		)
		(pad "2" smd custom
			(at 0 0.4445 180)
			(size 0.1397 0.1397)
			(layers "F.Cu" "F.Mask" "F.Paste")
			(net "MB3_RETRY_R")
			(options
				(clearance outline)
				(anchor circle)
			)
			(primitives
				(gr_poly
					(pts
						(arc
							(start -0.1778 -0.2794)
							(mid -0.249642 -0.249642)
							(end -0.2794 -0.1778)
						)
						(arc
							(start -0.2794 0.1778)
							(mid -0.249642 0.249642)
							(end -0.1778 0.2794)
						)
						(arc
							(start 0.1778 0.2794)
							(mid 0.249642 0.249642)
							(end 0.2794 0.1778)
						)
						(arc
							(start 0.2794 -0.1778)
							(mid 0.249642 -0.249642)
							(end 0.1778 -0.2794)
						)
					)
					(width 0)
					(fill yes)
				)
			)
		)
	)
	(footprint ""
		(layer "F.Cu")
		(at 472.899994 -209.399886)
		(property "Reference" "FLED12"
			(at 0 0 0)
			(layer "F.SilkS")
			(hide yes)
			(effects
				(font
					(size 1.27 1.27)
				)
			)
		)
		(property "Value" "LED-BY-19-GP"
			(at -2.132076 1.414018 0)
			(unlocked yes)
			(layer "F.Fab")
			(hide yes)
			(effects
				(font
					(size 1.016 1.016)
					(thickness 0.1524)
				)
			)
		)
		(property "Device Type" "LED-1615-4PH26"
			(at -2.132076 -0.109982 0)
			(unlocked yes)
			(layer "F.Fab")
			(hide yes)
			(effects
				(font
					(size 1.016 1.016)
					(thickness 0.1524)
				)
			)
		)
		(duplicate_pad_numbers_are_jumpers no)
		(fp_line
			(start -1.2954 0.254)
			(end -1.2954 1.6002)
			(stroke
				(width 0.508)
				(type default)
			)
			(layer "F.SilkS")
		)
		(fp_line
			(start -1.2954 1.6002)
			(end 1.2954 1.6002)
			(stroke
				(width 0.508)
				(type default)
			)
			(layer "F.SilkS")
		)
		(fp_line
			(start -1.1176 -1.4224)
			(end 1.1176 -1.4224)
			(stroke
				(width 0.1524)
				(type default)
			)
			(layer "F.SilkS")
		)
		(fp_line
			(start -1.1176 1.4224)
			(end -1.1176 -1.4224)
			(stroke
				(width 0.1524)
				(type default)
			)
			(layer "F.SilkS")
		)
		(fp_line
			(start 1.1176 -1.4224)
			(end 1.1176 1.4224)
			(stroke
				(width 0.1524)
				(type default)
			)
			(layer "F.SilkS")
		)
		(fp_line
			(start 1.1176 1.4224)
			(end -1.1176 1.4224)
			(stroke
				(width 0.1524)
				(type default)
			)
			(layer "F.SilkS")
		)
		(fp_line
			(start 1.2954 1.6002)
			(end 1.2954 0.254)
			(stroke
				(width 0.508)
				(type default)
			)
			(layer "F.SilkS")
		)
		(fp_rect
			(start -0.7493 0.8001)
			(end 0.7493 -0.8001)
			(stroke
				(width 0)
				(type default)
			)
			(fill no)
			(layer "F.CrtYd")
		)
		(fp_poly
			(pts
				(xy -1.3716 1.6764) (xy -1.3716 -1.6764) (xy 1.3716 -1.6764) (xy 1.3716 0.0635) (xy 0.7493 0.0635)
				(xy 0.7493 -0.8001) (xy -0.7493 -0.8001) (xy -0.7493 0.8001) (xy 0.7493 0.8001) (xy 0.7493 0.0762)
				(xy 1.3716 0.0762) (xy 1.3716 1.6764)
			)
			(stroke
				(width 0)
				(type default)
			)
			(fill no)
			(layer "F.CrtYd")
		)
		(fp_rect
			(start -1.3716 1.6764)
			(end 1.3716 -1.6764)
			(stroke
				(width 0)
				(type default)
			)
			(fill no)
			(layer "F.Fab")
		)
		(pad "1" smd rect
			(at 0.50038 -0.73025)
			(size 0.7112 0.8636)
			(layers "F.Cu" "F.Mask" "F.Paste")
			(net "DRV_ACT_11")
		)
		(pad "2" smd rect
			(at -0.50038 -0.73025)
			(size 0.7112 0.8636)
			(layers "F.Cu" "F.Mask" "F.Paste")
			(net "FLT_HDD11")
		)
		(pad "3" smd rect
			(at 0.50038 0.73025)
			(size 0.7112 0.8636)
			(layers "F.Cu" "F.Mask" "F.Paste")
			(net "DRV_ACT_11_N")
		)
		(pad "4" smd rect
			(at -0.50038 0.73025)
			(size 0.7112 0.8636)
			(layers "F.Cu" "F.Mask" "F.Paste")
			(net "FLT_HDD11_N")
		)
	)
	(footprint ""
		(layer "F.Cu")
		(at 253.873 -301.244 180)
		(property "Reference" "C1"
			(at 0 0 180)
			(layer "F.SilkS")
			(hide yes)
			(effects
				(font
					(size 1.27 1.27)
				)
			)
		)
		(property "Value" "SCD1U16V2KX-3GP"
			(at 1.1811 -2.7051 180)
			(unlocked yes)
			(layer "F.Fab")
			(hide yes)
			(effects
				(font
					(size 1.016 1.016)
					(thickness 0.1524)
				)
			)
		)
		(property "Device Type" "C402H22"
			(at 1.1811 -4.2291 180)
			(unlocked yes)
			(layer "F.Fab")
			(hide yes)
			(effects
				(font
					(size 1.016 1.016)
					(thickness 0.1524)
				)
			)
		)
		(duplicate_pad_numbers_are_jumpers no)
		(fp_rect
			(start -0.4318 0.9525)
			(end 0.4318 -0.9525)
			(stroke
				(width 0)
				(type default)
			)
			(fill no)
			(layer "F.CrtYd")
		)
		(fp_rect
			(start -0.4318 0.9525)
			(end 0.4318 -0.9525)
			(stroke
				(width 0)
				(type default)
			)
			(fill no)
			(layer "F.Fab")
		)
		(pad "1" smd custom
			(at 0 -0.4445 180)
			(size 0.1524 0.1524)
			(layers "F.Cu" "F.Mask" "F.Paste")
			(net "P3V3_STBY_A")
			(options
				(clearance outline)
				(anchor circle)
			)
			(primitives
				(gr_poly
					(pts
						(arc
							(start 0.3048 -0.2032)
							(mid 0.275042 -0.275042)
							(end 0.2032 -0.3048)
						)
						(arc
							(start -0.2032 -0.3048)
							(mid -0.275042 -0.275042)
							(end -0.3048 -0.2032)
						)
						(arc
							(start -0.3048 0.2032)
							(mid -0.275042 0.275042)
							(end -0.2032 0.3048)
						)
						(arc
							(start 0.2032 0.3048)
							(mid 0.275042 0.275042)
							(end 0.3048 0.2032)
						)
					)
					(width 0)
					(fill yes)
				)
			)
		)
		(pad "2" smd custom
			(at 0 0.4445 180)
			(size 0.1524 0.1524)
			(layers "F.Cu" "F.Mask" "F.Paste")
			(net "GND")
			(options
				(clearance outline)
				(anchor circle)
			)
			(primitives
				(gr_poly
					(pts
						(arc
							(start 0.3048 -0.2032)
							(mid 0.275042 -0.275042)
							(end 0.2032 -0.3048)
						)
						(arc
							(start -0.2032 -0.3048)
							(mid -0.275042 -0.275042)
							(end -0.3048 -0.2032)
						)
						(arc
							(start -0.3048 0.2032)
							(mid -0.275042 0.275042)
							(end -0.2032 0.3048)
						)
						(arc
							(start 0.2032 0.3048)
							(mid 0.275042 0.275042)
							(end 0.3048 0.2032)
						)
					)
					(width 0)
					(fill yes)
				)
			)
		)
	)
)
